FILE_TYPE = CONNECTIVITY;
{Allegro Design Entry HDL 16.6-p007 (v16-6-112F) 10/10/2012}
"PAGE_NUMBER" = 120;
0"NC";
1"GND\g";
2"JTAG_PCH_PLD_TCK";
3"FM_ADR_COMPLETE";
4"FM_CPLD_ADR_TRIGGER_N";
5"FM_CPLD_ADR_TRIGGER_R_N";
6"TP_PCH_GPP_F12";
7"FM_ADR_COMPLETE_R1";
8"FM_CPU_MSMI_LVT3_N";
9"IRQ_BMC_PCH_NMI_STBY_N";
10"FM_POST_CARD_PRES_BMC_N";
11"FM_ADR_SMI_GPIO_N";
12"FM_CPU_ERR2_LVT3_N";
13"IRQ_OC_DETECT_N";
14"FM_HSC_TIMER_EXP_N";
15"FM_MP_PS_FAIL_N";
16"FM_MP_PS_REDUNDANT_LOST_N";
17"FM_MEM_THERM_EVENT_PCH_N";
18"FM_BMC_READY_N";
19"FM_BIOS_TOP_SWAP";
20"SMB_LAN_STBY_LVC3_SCL_R2";
21"SMB_LAN_STBY_LVC3_SDA_R2";
22"FAN_TACH2";
23"FAN_TACH0";
24"IRQ_PVCCIN_CPU0_VRHOT_LVC3_N";
25"IRQ_PVCCIN_CPU1_VRHOT_LVC3_N";
26"FM_UARTSW_MSB_N";
27"FAN_PWM_OUT_SYS1";
28"FAN_PWM_OUT_SYS0";
29"FM_CPU0_FIVR_FAULT_LVT3_N";
30"FM_CPU1_FIVR_FAULT_LVT3_N";
31"FAN_TACH3";
32"FAN_TACH1";
33"FM_IE_DISABLE_N";
34"JTAG_PCH_PLD_TDI";
35"JTAG_PCH_PLD_TMS";
36"JTAG_PCH_PLD_TDO";
37"FM_BIOS_USB_RECOVERY";
38"FM_FORCE_ADR_N";
39"IRQ_PCH_NIC_ALERT_N";
40"SGPIO_PCH_SATA_LOAD";
41"SGPIO_PCH_SATA_CLOCK";
42"SGPIO_PCH_SSATA_LOAD";
43"SGPIO_PCH_SSATA_CLOCK";
44"SGPIO_PCH_SATA_DOUT0";
45"FM_THROTTLE_N";
46"FM_CPU1_THERMTRIP_LATCH_LVT3_N";
47"FM_CPU0_RC_ERROR_N";
48"FM_CPU0_RC_EN";
49"FM_CPU1_RC_ERROR_N";
50"LED_PCH_SSATA_HDD_N";
51"FM_SOL_UART_CH_SEL";
52"IRQ_FORCE_NM_THROTTLE_N";
53"FM_BIOS_SMI_ACTIVE_N";
54"FM_NMI_EVENT_N";
55"FM_BOARD_SKU_ID4";
56"FM_BOARD_SKU_ID2";
57"FM_BOARD_SKU_ID3";
58"FM_BOARD_SKU_ID1";
59"FM_BOARD_SKU_ID0";
60"FM_OC0_USB_N";
61"IRQ_BMC_PCH_SCI_LPC_N";
62"IRQ_BMC_PCH_SMI_LPC_N";
63"IRQ_UV_DETECT_N";
64"LED_PCH_SATA_HDD_N";
65"TP_PCH_GPP_J17";
66"TP_PCH_GPP_J19";
67"TP_PCH_GPP_J21";
68"TP_PCH_GPP_J23";
69"SMB_SENSOR_STBY_LVC3_SDA_R1";
70"FM_10GBE_LOM_DISABLE_N";
71"PU_10GBE_LOM_PCI_DISABLE_N";
72"PU_ADR_TIMER_HOLD_OFF_N";
73"JTAG_PCH_GBE_TDI";
74"JTAG_PCH_GBE_TMS";
75"JTAG_PCH_GBE_TDO";
76"JTAG_PCH_GBE_CLK";
77"SMB_VR_STBY_LVC3_SCL_R1";
78"JTAG_PCH_GBE_TRST_N";
79"FM_BACKUP_BIOS_SEL_N";
80"LED_POSTCODE_7";
81"LED_POSTCODE_6";
82"LED_POSTCODE_5";
83"LED_POSTCODE_4";
84"LED_POSTCODE_3";
85"LED_POSTCODE_2";
86"LED_POSTCODE_1";
87"LED_POSTCODE_0";
88"FM_UARTSW_LSB_N";
89"IRQ_DIMM_SAVE_LVT3_N";
90"IRQ_BOARD_BMC_ALERT_N";
91"FM_BIOS_MRC_DEBUG_MSG_DIS_N";
92"FM_OC_DETECT_EN_N";
93"LED_GBE_P0_0";
94"LED_GBE_P0_1";
95"LED_GBE_P1_0";
96"LED_GBE_P1_1";
97"LED_GBE_P3_1";
98"SMB_PCH_MEZZ_LOM0_SCL";
99"SMB_PCH_MEZZ_LOM1_SCL";
100"SMB_PCH_MEZZ_LOM0_SDA";
101"SMB_PCH_MEZZ_LOM1_SDA";
102"FM_GBE3_LVC3_MOD_ABS";
103"FM_GBE2_LVC3_MOD_ABS";
104"FM_GBE1_LVC3_MOD_ABS";
105"FM_GBE0_LVC3_MOD_ABS";
106"LED_GBE_P2_0";
107"LED_GBE_P2_1";
108"LED_GBE_P3_0";
109"SMB_PCH_MEZZ_LOM2_SCL";
110"SMB_PCH_MEZZ_LOM2_SDA";
111"SMB_PCH_MEZZ_LOM3_SDA";
112"SMB_PCH_MEZZ_LOM3_SCL";
113"FM_FLASH_ATTACH_CFG_STRAP";
114"FM_CPU1_RC_ERROR_N";
115"SMB_LAN_STBY_LVC3_SCL_R1";
116"SMB_LAN_STBY_LVC3_SDA_R1";
117"SMB_VR_STBY_LVC3_SDA_R1";
118"SMB_SENSOR_STBY_LVC3_SCL_R1";
119"A_RCOMP_3P3";
120"FM_BIOS_SMI_ACTIVE_N";
121"FM_BMC_NMI_N";
122"FM_SSATA_PCIE_M2_SEL";
123"FM_PCH_BMC_THERMTRIP_N";
124"FP_PWR_ID_LED_N";
%"LBG_CORE_QAT_EXT_D"
"7","(-3975,2800)","0","mstr_u_proc","I147";
;
CDS_SEC"7"
PACK_TYPE"BGA1"
ROOM"SB"
SEC_TYPE"BGA1"
SEC"7"
CDS_LIB"mstr_u_proc"
BOM_COST"SB"
CDS_LOCATION"U7C1"
LOCATION"U7C1"
PART_NUMBER"H91415-002"
MATERIAL"IC";
"GPP_J9_LAN_I2C_SDA_MDIO_P0"
$PN"BN3"100;
"GPP_J8_LAN_I2C_SCL_MDC_P0"
$PN"BM4"98;
"GPP_J7_LAN_LED_P3_1"
$PN"BM2"97;
"GPP_J6_LAN_LED_P3_0"
$PN"CA13"108;
"GPP_J5_LAN_LED_P2_1"
$PN"BU6"107;
"GPP_J4_LAN_LED_P2_0"
$PN"BL3"106;
"GPP_J3_LAN_LED_P1_1"
$PN"BK2"96;
"GPP_J2_LAN_LED_P1_0"
$PN"BP4"95;
"GPP_J23_LAN_SDP_P3_1"
$PN"BV14"68;
"GPP_J22_LAN_SDP_P3_0"
$PN"BY12"102;
"GPP_J21_LAN_SDP_P2_1"
$PN"BV12"67;
"GPP_J20_LAN_SDP_P2_0"
$PN"BW13"103;
"GPP_J1_LAN_LED_P0_1"
$PN"BK4"94;
"GPP_J19_LAN_SDP_P1_1"
$PN"BY14"66;
"GPP_J18_LAN_SDP_P1_0"
$PN"BY10"104;
"GPP_J17_LAN_SDP_P0_1"
$PN"CA11"65;
"GPP_J16_LAN_SDP_P0_0"
$PN"BV10"105;
"GPP_J15_LAN_I2C_SDA_MDIO_P3"
$PN"BW9"111;
"GPP_J14_LAN_I2C_SCL_MDC_P3"
$PN"BW6"112;
"GPP_J13_LAN_I2C_SDA_MDIO_P2"
$PN"BW11"110;
"GPP_J12_LAN_I2C_SCL_MDC_P2"
$PN"BT5"109;
"GPP_J11_LAN_I2C_SDA_MDIO_P1"
$PN"BV8"101;
"GPP_J10_LAN_I2C_SCL_MDC_P1"
$PN"BW5"99;
"GPP_J0_LAN_LED_P0_0"
$PN"BL1"93;
"GPP_I9_LAN_DIS_N"
$PN"BY21"70;
"GPP_I8_PCI_DIS_N"
$PN"BW22"71;
"GPP_I7_LAN_TRST_N"
$PN"CA24"78;
"GPP_I6_RESET_DONE"
$PN"BV23"114;
"GPP_I5_DO_RESET_OUT_N"
$PN"BW24"90;
"GPP_I4_DO_RESET_IN_N"
$PN"BW20"89;
"GPP_I3_LAN_TDI"
$PN"BY23"73;
"GPP_I2_LAN_TMS"
$PN"CA22"74;
"GPP_I1_LAN_TCK"
$PN"BV21"76;
"GPP_I10"
$PN"BV25"91;
"GPP_I0_LAN_TDO"
$PN"CA20"75;
"GPP_H9_SRCCLKREQ15_N"
$PN"BE2"80;
"GPP_H8_SRCCLKREQ14_N"
$PN"AR3"81;
"GPP_H7_SRCCLKREQ13_N"
$PN"AV1"82;
"GPP_H6_SRCCLKREQ12_N"
$PN"AW2"83;
"GPP_H5_SRCCLKREQ11_N"
$PN"AY3"84;
"GPP_H4_SRCCLKREQ10_N"
$PN"AT2"85;
"GPP_H3_SRCCLKREQ9_N"
$PN"AR1"86;
"GPP_H2_SRCCLKREQ8_N"
$PN"AV3"87;
"GPP_H23_SSATAXPCIE5_SSATAGP5"
$PN"BH4"122;
"GPP_H22_SSATAXPCIE4_SSATAGP4"
$PN"BH2"123;
"GPP_H21_SSATAXPCIE3_SSATAGP3"
$PN"BA2"120;
"GPP_H20_SSATAXPCIE2_SSATAGP2"
$PN"BF3"121;
"GPP_H1_SRCCLKREQ7_N"
$PN"AW4"79;
"GPP_H19_SSATAXPCIE1_SSATAGP1"
$PN"BD3"124;
"GPP_H18_SML4ALERT_N_IE_N"
$PN"BC4"92;
"GPP_H17_SML4DATA_IE"
$PN"BE4"116;
"GPP_H16_SML4CLK_IE"
$PN"BF1"115;
"GPP_H15_SML3ALERT_N_IE_N"
$PN"BB3"72;
"GPP_H14_SML3DATA_IE"
$PN"BC2"69;
"GPP_H13_SML3CLK_IE"
$PN"AY1"118;
"GPP_H12_SML2ALERT_N_IE_N"
$PN"BB1"113;
"GPP_H11_SML2DATA_IE"
$PN"BD1"117;
"GPP_H10_SML2CLK_IE"
$PN"BA4"77;
"GPP_H0_SRCCLKREQ6_N"
$PN"AT4"88;
"GPP_G9_FANPWM1_FAMPWM1IE"
$PN"AV11"27;
"GPP_G8_FANPWM0_FANPWM0IE"
$PN"BG11"28;
"GPP_G7_FANTACH7_FANTACH7IE"
$PN"AY15"45;
"GPP_G6_FANTACH6_FANTACH6IE"
$PN"AV18"46;
"GPP_G5_FANTACH5_FANTACH5IE"
$PN"AW20"25;
"GPP_G4_FANTACH4_FANTACH4IE"
$PN"BA9"24;
"GPP_G3_FANTACH3_FANTACH3IE"
$PN"AY7"31;
"GPP_G2_FANTACH2_FANTACH2IE"
$PN"BE22"22;
"GPP_G23_SSATAXPCIE0_SSATAGP0"
$PN"BA13"26;
"GPP_G22_SSATA_DEVSLP2"
$PN"BD20"48;
"GPP_G21_SSATA_DEVSLP1"
$PN"BG7"51;
"GPP_G20_SSATA_DEVSLP0"
$PN"BA17"52;
"GPP_G1_FANTACH1_FANTACH1IE"
$PN"AV15"32;
"GPP_G19_SMI_N"
$PN"BE15"53;
"GPP_G18_NMI_N"
$PN"BE7"54;
"GPP_G17_ADR_COMPLETE"
$PN"BD9"7;
"GPP_G16"
$PN"BD17"55;
"GPP_G15"
$PN"BE18"57;
"GPP_G14"
$PN"AV7"56;
"GPP_G13"
$PN"AY18"58;
"GPP_G12"
$PN"BD13"59;
"GPP_G11_FANPWM3_FANPMW3IE"
$PN"BA20"30;
"GPP_G10_FANPWM2_FANPWM2IE"
$PN"BE11"29;
"GPP_G0_FANTACH0_FANTACH0IE"
$PN"AY11"23;
"GPP_F9_SATA_DEVSLP7"
$PN"AR20"36;
"GPP_F8_SATA_DEVSLP6"
$PN"AH9"35;
"GPP_F7_SATA_DEVSLP5"
$PN"AK17"34;
"GPP_F6_SATA_DEVSLP4"
$PN"AL18"2;
"GPP_F5_SATA_DEVSLP3"
$PN"AH17"37;
"GPP_F4_SATAXPCIE7_SATAGP7"
$PN"AH13"18;
"GPP_F3_SATAXPCIE6_SATAGP6"
$PN"AK13"16;
"GPP_F2_SATAXPCIE5_SATAGP5"
$PN"AK20"15;
"GPP_F23_SSATA_SLOAD"
$PN"AU17"42;
"GPP_F22_SSATA_SCLOCK"
$PN"AP18"43;
"GPP_F21_LAN_SMBALRT_N"
$PN"AR17"39;
"GPP_F20_LAN_SMBDATA"
$PN"AU20"21;
"GPP_F1_SATAXPCIE4_SATAGP4"
$PN"AK9"14;
"GPP_F19_LAN_SMBCLK"
$PN"AU9"20;
"GPP_F18_USB2_OC7_N"
$PN"AL15"17;
"GPP_F17_USB2_OC6_N"
$PN"AP15"19;
"GPP_F16_USB2_OC5_N"
$PN"AU13"33;
"GPP_F15_USB2_OC4_N"
$PN"AR13"38;
"GPP_F14_SSATA_LED_N"
$PN"AL11"50;
"GPP_F13_SATA_SDATAOUT0"
$PN"AP11"44;
"GPP_F12_SATA_SDATAOUT1"
$PN"AP7"6;
"GPP_F11_SATA_SLOAD"
$PN"AR9"40;
"GPP_F10_SATA_SCLOCK"
$PN"AL7"41;
"GPP_F0_SATAXPCIE3_SATAGP3"
$PN"AG7"13;
"GPP_E9_USB2_OC0_N"
$PN"BL48"60;
"GPP_E8_SATA_LED_N"
$PN"AV56"64;
"GPP_E7_CPU_GP1"
$PN"BJ48"11;
"GPP_E6_SATA_DEVSLP2"
$PN"BB52"9;
"GPP_E5_SATA_DEVSLP1"
$PN"AT52"8;
"GPP_E4_SATA_DEVSLP0"
$PN"AV52"12;
"GPP_E3_CPU_GP0"
$PN"BE52"5;
"GPP_E2_SATAXPCIE2_SATAGP2"
$PN"BG52"10;
"GPP_E1_SATAXPCIE1_SATAGP1"
$PN"AY52"49;
"GPP_E12_USB2_OC3_N"
$PN"AU58"63;
"GPP_E11_USB2_OC2_N"
$PN"AW54"62;
"GPP_E10_USB2_OC1_N"
$PN"BN48"61;
"GPP_E0_SATAXPCIE0_SATAGP0"
$PN"BH50"47;
"GPIO_RCOMP_3P3"
$PN"BY25"119;
%"RES"
"2","(-775,2825)","0","mstr_discrete","I148";
;
CDS_SEC"1"
ROOM"SB"
SEC"1"
SEC_TYPE"0402"
CDS_LOCATION"R8C21"
CDS_LIB"mstr_discrete"
LOCATION"R8C21"
PART_NUMBER"G21796-017"
VALUE"100.0"
TOLERANCE"1%"
PACK_TYPE"0402"
MATERIAL"CHIP"
WATTAGE"1/16W";
"A"
$PN"1"119;
"B"
$PN"2"1;
%"RES"
"1","(-6375,3850)","0","mstr_discrete","I218";
;
CDS_SEC"1"
ROOM"CPLD"
CDS_LOCATION"R2M1"
SEC"1"
SEC_TYPE"0402"
CDS_LIB"mstr_discrete"
LOCATION"R2M1"
PART_NUMBER"G21796-074"
VALUE"33.2"
TOLERANCE"1%"
PACK_TYPE"0402"
MATERIAL"CHIP"
WATTAGE"1/16W";
"B"
$PN"2"5;
"A"
$PN"1"4;
%"RES"
"1","(-6325,2050)","0","mstr_discrete","I219";
;
CDS_SEC"1"
ROOM"CPLD"
CDS_LOCATION"R2N26"
SEC"1"
SEC_TYPE"0402"
CDS_LIB"mstr_discrete"
LOCATION"R2N26"
PART_NUMBER"G21796-074"
VALUE"33.2"
TOLERANCE"1%"
PACK_TYPE"0402"
MATERIAL"CHIP"
WATTAGE"1/16W";
"B"
$PN"2"7;
"A"
$PN"1"3;
%"GND"
"1","(-775,2600)","0","mstr_symbols","I266";
;
VOLTAGE"0.0V"
HDL_POWER"GND"
CDS_LIB"mstr_symbols"
SIZE"1B"
BODY_TYPE"PLUMBING";
"A\NAC"1;
END.
